(kicad_pcb
	(version 20241229)
	(generator "pcbnew")
	(generator_version "9.0")
	(general
		(thickness 1.294)
		(legacy_teardrops no)
	)
	(paper "A3")
	(title_block
		(title "Kintex 410T devboard")
		(date "2024-04-03")
		(rev "1.1.2")
		(comment 9 "footprints 61-64 of 975")
	)
	(layers
		(0 "F.Cu" mixed)
		(4 "In1.Cu" power)
		(6 "In2.Cu" power)
		(8 "In3.Cu" mixed)
		(10 "In4.Cu" power)
		(12 "In5.Cu" mixed)
		(14 "In6.Cu" power)
		(16 "In7.Cu" mixed)
		(18 "In8.Cu" power)
		(2 "B.Cu" mixed)
		(9 "F.Adhes" user "F.Adhesive")
		(11 "B.Adhes" user "B.Adhesive")
		(13 "F.Paste" user)
		(15 "B.Paste" user)
		(5 "F.SilkS" user "F.Silkscreen")
		(7 "B.SilkS" user "B.Silkscreen")
		(1 "F.Mask" user)
		(3 "B.Mask" user)
		(17 "Dwgs.User" user "User.Drawings")
		(19 "Cmts.User" user "User.Comments")
		(21 "Eco1.User" user "User.Eco1")
		(23 "Eco2.User" user "User.Eco2")
		(25 "Edge.Cuts" user)
		(27 "Margin" user)
		(31 "F.CrtYd" user "F.Courtyard")
		(29 "B.CrtYd" user "B.Courtyard")
		(35 "F.Fab" user)
		(33 "B.Fab" user)
	)
	(footprint "antmicro-footprints:R_0402_1005Metric"
		(layer "F.Cu")
		(at 244.15 103.3)
		(descr "Resistor SMD 0402")
		(tags "resistor SMD 0402")
		(property "Reference" "R255"
			(at 0.8 0.35 0)
			(layer "F.SilkS")
			(effects
				(font
					(size 0.7 0.7)
					(thickness 0.15)
				)
				(justify left bottom)
			)
		)
		(property "Value" "R_0R_0402"
			(at 0 1.4 0)
			(layer "F.Fab")
			(effects
				(font
					(size 0.7 0.7)
					(thickness 0.15)
				)
				(justify left bottom)
			)
		)
		(property "Description" "SMD Chip Resistor, Jumper, 0 ohm, 100 mW, 0402 [1005 Metric], Thick Film, General Purpose"
			(at 0 0 0)
			(layer "F.Fab")
			(hide yes)
			(effects
				(font
					(size 1.27 1.27)
					(thickness 0.15)
				)
			)
		)
		(property "Author" "Antmicro"
			(at 0 0 0)
			(layer "F.Fab")
			(hide yes)
			(effects
				(font
					(size 1 1)
					(thickness 0.15)
				)
			)
		)
		(property "Current" "1A"
			(at 0 0 0)
			(layer "F.Fab")
			(hide yes)
			(effects
				(font
					(size 1 1)
					(thickness 0.15)
				)
			)
		)
		(property "License" "Apache-2.0"
			(at 0 0 0)
			(layer "F.Fab")
			(hide yes)
			(effects
				(font
					(size 1 1)
					(thickness 0.15)
				)
			)
		)
		(property "MPN" "ERJ2GE0R00X"
			(at 0 0 0)
			(layer "F.Fab")
			(hide yes)
			(effects
				(font
					(size 1 1)
					(thickness 0.15)
				)
			)
		)
		(property "Manufacturer" "Panasonic"
			(at 0 0 0)
			(layer "F.Fab")
			(hide yes)
			(effects
				(font
					(size 1 1)
					(thickness 0.15)
				)
			)
		)
		(property "Tolerance" ""
			(at 0 0 0)
			(layer "F.Fab")
			(hide yes)
			(effects
				(font
					(size 1 1)
					(thickness 0.15)
				)
			)
		)
		(property "Val" "0R"
			(at 0 0 0)
			(layer "F.Fab")
			(hide yes)
			(effects
				(font
					(size 1 1)
					(thickness 0.15)
				)
			)
		)
		(sheetname "HDMI + Ethernet")
		(sheetfile "hdmi-ethernet.kicad_sch")
		(attr smd)
		(fp_rect
			(start -0.925 -0.47)
			(end 0.925 0.47)
			(stroke
				(width 0.05)
				(type default)
			)
			(fill no)
			(layer "F.CrtYd")
		)
		(fp_rect
			(start -0.5 -0.25)
			(end 0.5 0.25)
			(stroke
				(width 0.15)
				(type solid)
			)
			(fill no)
			(layer "F.Fab")
		)
		(pad "1" smd roundrect
			(at -0.48 0)
			(size 0.59 0.64)
			(layers "F.Cu" "F.Mask" "F.Paste")
			(roundrect_rratio 0.25)
			(net 525 "/FPGA Bank 16 & 17/HDMI.D2_N")
			(pintype "passive")
		)
		(pad "2" smd roundrect
			(at 0.48 0)
			(size 0.59 0.64)
			(layers "F.Cu" "F.Mask" "F.Paste")
			(roundrect_rratio 0.25)
			(net 866 "/HDMI + Ethernet/HDMI_CONN_D2_N")
			(pintype "passive")
		)
	)
	(footprint "antmicro-footprints:Vishay_PowerPAK_1212-8_Single"
		(layer "F.Cu")
		(at 190.025 179.999)
		(descr "PowerPAK 1212-8 Single")
		(tags "Vishay PowerPAK 1212-8 Single")
		(property "Reference" "Q7"
			(at 2.925 1.901 90)
			(layer "F.SilkS")
			(effects
				(font
					(size 0.7 0.7)
					(thickness 0.15)
				)
				(justify left bottom)
			)
		)
		(property "Value" "SI7613DN-T1-GE3"
			(at -8 2.7 0)
			(layer "F.Fab")
			(effects
				(font
					(size 0.7 0.7)
					(thickness 0.15)
				)
				(justify left bottom)
			)
		)
		(property "Description" "Power MOSFET, P Channel, 20 V, 35 A, 0.0072 ohm, PowerPAK 1212, Surface Mount"
			(at 0 0 0)
			(layer "F.Fab")
			(hide yes)
			(effects
				(font
					(size 1.27 1.27)
					(thickness 0.15)
				)
			)
		)
		(property "Author" "Antmicro"
			(at 0 0 0)
			(layer "F.Fab")
			(hide yes)
			(effects
				(font
					(size 1 1)
					(thickness 0.15)
				)
			)
		)
		(property "License" "Apache-2.0"
			(at 0 0 0)
			(layer "F.Fab")
			(hide yes)
			(effects
				(font
					(size 1 1)
					(thickness 0.15)
				)
			)
		)
		(property "MPN" "SI7613DN-T1-GE3"
			(at 0 0 0)
			(layer "F.Fab")
			(hide yes)
			(effects
				(font
					(size 1 1)
					(thickness 0.15)
				)
			)
		)
		(property "Manufacturer" "Vishay"
			(at 0 0 0)
			(layer "F.Fab")
			(hide yes)
			(effects
				(font
					(size 1 1)
					(thickness 0.15)
				)
			)
		)
		(sheetname "Power supply")
		(sheetfile "power-supply.kicad_sch")
		(attr smd)
		(fp_line
			(start -1.651 -1.651)
			(end -1.651 -1.317)
			(stroke
				(width 0.15)
				(type solid)
			)
			(layer "F.SilkS")
		)
		(fp_line
			(start -1.651 -1.651)
			(end 1.648 -1.651)
			(stroke
				(width 0.15)
				(type solid)
			)
			(layer "F.SilkS")
		)
		(fp_line
			(start -1.635 1.3)
			(end -1.635 1.634)
			(stroke
				(width 0.15)
				(type solid)
			)
			(layer "F.SilkS")
		)
		(fp_line
			(start -1.635 1.634)
			(end 1.634 1.634)
			(stroke
				(width 0.15)
				(type solid)
			)
			(layer "F.SilkS")
		)
		(fp_line
			(start 1.634 1.3)
			(end 1.634 1.634)
			(stroke
				(width 0.15)
				(type solid)
			)
			(layer "F.SilkS")
		)
		(fp_line
			(start 1.648 -1.651)
			(end 1.648 -1.317)
			(stroke
				(width 0.15)
				(type solid)
			)
			(layer "F.SilkS")
		)
		(fp_circle
			(center -1.9 -1.4)
			(end -1.85 -1.4)
			(stroke
				(width 0.15)
				(type solid)
			)
			(fill yes)
			(layer "F.SilkS")
		)
		(fp_rect
			(start -2 -1.8)
			(end 2 1.798)
			(stroke
				(width 0.05)
				(type solid)
			)
			(fill no)
			(layer "F.CrtYd")
		)
		(fp_line
			(start -1.6425 -1.4175)
			(end -1.4175 -1.6425)
			(stroke
				(width 0.15)
				(type solid)
			)
			(layer "F.Fab")
		)
		(fp_rect
			(start -1.651 -1.651)
			(end 1.648 1.648)
			(stroke
				(width 0.15)
				(type solid)
			)
			(fill no)
			(layer "F.Fab")
		)
		(pad "1" smd rect
			(at -1.436 -0.99)
			(size 0.99 0.405)
			(layers "F.Cu" "F.Mask" "F.Paste")
			(net 702 "VDC")
			(pinfunction "S")
			(pintype "passive")
		)
		(pad "2" smd rect
			(at -1.436 -0.332)
			(size 0.99 0.405)
			(layers "F.Cu" "F.Mask" "F.Paste")
			(net 702 "VDC")
			(pinfunction "S")
			(pintype "passive")
		)
		(pad "3" smd rect
			(at -1.436 0.33)
			(size 0.99 0.405)
			(layers "F.Cu" "F.Mask" "F.Paste")
			(net 702 "VDC")
			(pinfunction "S")
			(pintype "passive")
		)
		(pad "4" smd rect
			(at -1.436 0.988)
			(size 0.99 0.405)
			(layers "F.Cu" "F.Mask" "F.Paste")
			(net 342 "Net-(Q7-G)")
			(pinfunction "G")
			(pintype "passive")
		)
		(pad "5" smd custom
			(at 0.557 0)
			(size 1.725 2.235)
			(layers "F.Cu" "F.Mask" "F.Paste")
			(net 956 "/DC-DC Converters/POE_DC")
			(pinfunction "D")
			(pintype "passive")
			(zone_connect 2)
			(options
				(clearance outline)
				(anchor rect)
			)
			(primitives
				(gr_poly
					(pts
						(xy 0.8625 0.1275) (xy 0.8625 -0.1275) (xy 1.3725 -0.1275) (xy 1.3725 -0.5325) (xy 0.8625 -0.5325)
						(xy 0.8625 -0.7875) (xy 1.3725 -0.7875) (xy 1.3725 -1.195) (xy 0.6125 -1.195) (xy 0.6125 1.195)
						(xy 1.3725 1.195) (xy 1.3725 0.7875) (xy 0.8625 0.7875) (xy 0.8625 0.5325) (xy 1.3725 0.5325)
						(xy 1.3725 0.1275)
					)
					(width 0)
					(fill yes)
				)
			)
		)
	)
	(footprint "antmicro-footprints:R_0402_1005Metric"
		(layer "F.Cu")
		(at 170.4 188.7)
		(descr "Resistor SMD 0402")
		(tags "resistor SMD 0402")
		(property "Reference" "R308"
			(at -1.2 -0.55 0)
			(layer "F.SilkS")
			(effects
				(font
					(size 0.7 0.7)
					(thickness 0.15)
				)
				(justify left bottom)
			)
		)
		(property "Value" "R_0R_0402"
			(at 0 1.4 0)
			(layer "F.Fab")
			(effects
				(font
					(size 0.7 0.7)
					(thickness 0.15)
				)
				(justify left bottom)
			)
		)
		(property "Description" "SMD Chip Resistor, Jumper, 0 ohm, 100 mW, 0402 [1005 Metric], Thick Film, General Purpose"
			(at 0 0 0)
			(layer "F.Fab")
			(hide yes)
			(effects
				(font
					(size 1.27 1.27)
					(thickness 0.15)
				)
			)
		)
		(property "Author" "Antmicro"
			(at 0 0 0)
			(layer "F.Fab")
			(hide yes)
			(effects
				(font
					(size 1 1)
					(thickness 0.15)
				)
			)
		)
		(property "Current" "1A"
			(at 0 0 0)
			(layer "F.Fab")
			(hide yes)
			(effects
				(font
					(size 1 1)
					(thickness 0.15)
				)
			)
		)
		(property "License" "Apache-2.0"
			(at 0 0 0)
			(layer "F.Fab")
			(hide yes)
			(effects
				(font
					(size 1 1)
					(thickness 0.15)
				)
			)
		)
		(property "MPN" "ERJ2GE0R00X"
			(at 0 0 0)
			(layer "F.Fab")
			(hide yes)
			(effects
				(font
					(size 1 1)
					(thickness 0.15)
				)
			)
		)
		(property "Manufacturer" "Panasonic"
			(at 0 0 0)
			(layer "F.Fab")
			(hide yes)
			(effects
				(font
					(size 1 1)
					(thickness 0.15)
				)
			)
		)
		(property "Tolerance" ""
			(at 0 0 0)
			(layer "F.Fab")
			(hide yes)
			(effects
				(font
					(size 1 1)
					(thickness 0.15)
				)
			)
		)
		(property "Val" "0R"
			(at 0 0 0)
			(layer "F.Fab")
			(hide yes)
			(effects
				(font
					(size 1 1)
					(thickness 0.15)
				)
			)
		)
		(sheetname "DC-DC Converters")
		(sheetfile "dc-dc.kicad_sch")
		(attr smd)
		(fp_rect
			(start -0.925 -0.47)
			(end 0.925 0.47)
			(stroke
				(width 0.05)
				(type default)
			)
			(fill no)
			(layer "F.CrtYd")
		)
		(fp_rect
			(start -0.5 -0.25)
			(end 0.5 0.25)
			(stroke
				(width 0.15)
				(type solid)
			)
			(fill no)
			(layer "F.Fab")
		)
		(pad "1" smd roundrect
			(at -0.48 0)
			(size 0.59 0.64)
			(layers "F.Cu" "F.Mask" "F.Paste")
			(roundrect_rratio 0.25)
			(net 14 "/DC-DC Converters/SEQ_EN")
			(pintype "passive")
		)
		(pad "2" smd roundrect
			(at 0.48 0)
			(size 0.59 0.64)
			(layers "F.Cu" "F.Mask" "F.Paste")
			(roundrect_rratio 0.25)
			(net 961 "/DC-DC Converters/ON{slash}OFF")
			(pintype "passive")
		)
	)
	(footprint "antmicro-footprints:UQFN-16-1.8x2.6mm_P0.4mm_Texas_RSV0016A"
		(layer "F.Cu")
		(at 233.7 148.4)
		(descr "https://www.ti.com/lit/ds/symlink/sn74avch4t245-ep.pdf?ts=1679484181203&ref_url=https%253A%252F%252Fwww.ti.com%252Fproduct%252FSN74AVCH4T245-EP%253Futm_source%253Dgoogle%2526utm_medium%253Dcpc%2526utm_campaign%253Dasc-int-null-prodfolderdynamic-cpc-pf-google-wwe_int%2526utm_content%253Dprodfolddynamic%2526ds_k%253DDYNAMIC%2BSEARCH%2BADS%2526DCM%253Dyes%2526gclid%253DCjwKCAjwzuqgBhAcEiwAdj5dRvR_WgyvqqhLxMx8zfbFv2a6tg33JIMv01Bn4M1kA4JzW1nDDW7OzhoCRbkQAvD_BwE%2526gclsrc%253Daw.ds")
		(property "Reference" "U25"
			(at -1.35 1.45 90)
			(layer "F.SilkS")
			(effects
				(font
					(size 0.7 0.7)
					(thickness 0.15)
				)
				(justify left bottom)
			)
		)
		(property "Value" "TUSB1106RSVR"
			(at -1.25 2.5 0)
			(layer "F.Fab")
			(effects
				(font
					(size 0.7 0.7)
					(thickness 0.15)
				)
				(justify left bottom)
			)
		)
		(property "Description" "1/1 Transceiver Half USB 2.0 16-UQFN"
			(at 0 0 0)
			(layer "F.Fab")
			(hide yes)
			(effects
				(font
					(size 1.27 1.27)
					(thickness 0.15)
				)
			)
		)
		(property "Author" "Antmicro"
			(at 0 0 0)
			(layer "F.Fab")
			(hide yes)
			(effects
				(font
					(size 1 1)
					(thickness 0.15)
				)
			)
		)
		(property "License" "Apache-2.0"
			(at 0 0 0)
			(layer "F.Fab")
			(hide yes)
			(effects
				(font
					(size 1 1)
					(thickness 0.15)
				)
			)
		)
		(property "MPN" "TUSB1106RSVR"
			(at 0 0 0)
			(layer "F.Fab")
			(hide yes)
			(effects
				(font
					(size 1 1)
					(thickness 0.15)
				)
			)
		)
		(property "Manufacturer" "Texas Instruments"
			(at 0 0 0)
			(layer "F.Fab")
			(hide yes)
			(effects
				(font
					(size 1 1)
					(thickness 0.15)
				)
			)
		)
		(sheetname "USB PHY")
		(sheetfile "usb-phy.kicad_sch")
		(attr smd)
		(fp_line
			(start -0.9 1.2995)
			(end -0.9 0.8)
			(stroke
				(width 0.15)
				(type solid)
			)
			(layer "F.SilkS")
		)
		(fp_line
			(start -0.8 -1.3)
			(end -0.9 -1.3)
			(stroke
				(width 0.15)
				(type solid)
			)
			(layer "F.SilkS")
		)
		(fp_line
			(start -0.8 1.2995)
			(end -0.9 1.2995)
			(stroke
				(width 0.15)
				(type solid)
			)
			(layer "F.SilkS")
		)
		(fp_line
			(start 0.8 -1.3)
			(end 0.9 -1.3)
			(stroke
				(width 0.15)
				(type solid)
			)
			(layer "F.SilkS")
		)
		(fp_line
			(start 0.8 1.3)
			(end 0.899 1.3)
			(stroke
				(width 0.15)
				(type solid)
			)
			(layer "F.SilkS")
		)
		(fp_line
			(start 0.9 -1.3)
			(end 0.9 -0.8005)
			(stroke
				(width 0.15)
				(type solid)
			)
			(layer "F.SilkS")
		)
		(fp_line
			(start 0.9 0.8)
			(end 0.899 1.3)
			(stroke
				(width 0.15)
				(type solid)
			)
			(layer "F.SilkS")
		)
		(fp_rect
			(start -1.25 -1.65)
			(end 1.25 1.65)
			(stroke
				(width 0.05)
				(type solid)
			)
			(fill no)
			(layer "F.CrtYd")
		)
		(fp_line
			(start -0.902 1.3)
			(end -0.902 -1.301)
			(stroke
				(width 0.15)
				(type solid)
			)
			(layer "F.Fab")
		)
		(fp_line
			(start 0.9 -1.301)
			(end -0.902 -1.301)
			(stroke
				(width 0.15)
				(type solid)
			)
			(layer "F.Fab")
		)
		(fp_line
			(start 0.9 1.3)
			(end -0.902 1.3)
			(stroke
				(width 0.15)
				(type solid)
			)
			(layer "F.Fab")
		)
		(fp_line
			(start 0.9 1.3)
			(end 0.9 -1.301)
			(stroke
				(width 0.15)
				(type solid)
			)
			(layer "F.Fab")
		)
		(fp_text user "."
			(at -1.45 -0.75 0)
			(layer "F.SilkS")
			(effects
				(font
					(size 0.7 0.7)
					(thickness 0.15)
				)
				(justify left bottom)
			)
		)
		(pad "1" smd roundrect
			(at -0.75 -0.6)
			(size 0.7 0.2)
			(layers "F.Cu" "F.Mask" "F.Paste")
			(roundrect_rratio 0.2272727273)
			(net 498 "/FPGA Bank 12 & 13/USB_USER.~{OE}")
			(pinfunction "~{OE}")
			(pintype "input")
		)
		(pad "2" smd roundrect
			(at -0.802 -0.202)
			(size 0.6 0.2)
			(layers "F.Cu" "F.Mask" "F.Paste")
			(roundrect_rratio 0.2272727273)
			(net 587 "/FPGA Bank 12 & 13/USB_USER.RCV")
			(pinfunction "RCV")
			(pintype "output")
		)
		(pad "3" smd roundrect
			(at -0.802 0.2)
			(size 0.6 0.2)
			(layers "F.Cu" "F.Mask" "F.Paste")
			(roundrect_rratio 0.2272727273)
			(net 584 "/FPGA Bank 12 & 13/USB_USER.VP")
			(pinfunction "VP")
			(pintype "output")
		)
		(pad "4" smd roundrect
			(at -0.802 0.598)
			(size 0.6 0.2)
			(layers "F.Cu" "F.Mask" "F.Paste")
			(roundrect_rratio 0.2272727273)
			(net 1397 "/FPGA Bank 12 & 13/USB_USER.VM")
			(pinfunction "VM")
			(pintype "output")
		)
		(pad "5" smd roundrect
			(at -0.6 1.199 90)
			(size 0.6 0.2)
			(layers "F.Cu" "F.Mask" "F.Paste")
			(roundrect_rratio 0.2272727273)
			(net 500 "/FPGA Bank 12 & 13/USB_USER.SUS")
			(pinfunction "SUSPND")
			(pintype "input")
		)
		(pad "6" smd roundrect
			(at -0.202 1.199 90)
			(size 0.6 0.2)
			(layers "F.Cu" "F.Mask" "F.Paste")
			(roundrect_rratio 0.2272727273)
			(net 1 "GND")
			(pinfunction "GND")
			(pintype "power_in")
		)
		(pad "7" smd roundrect
			(at 0.2 1.199 90)
			(size 0.6 0.2)
			(layers "F.Cu" "F.Mask" "F.Paste")
			(roundrect_rratio 0.2272727273)
			(net 26 "+1V8")
			(pinfunction "VCCIO")
			(pintype "power_in")
		)
		(pad "8" smd roundrect
			(at 0.598 1.199 90)
			(size 0.6 0.2)
			(layers "F.Cu" "F.Mask" "F.Paste")
			(roundrect_rratio 0.2272727273)
			(net 616 "/FPGA Bank 12 & 13/USB_USER.SPD")
			(pinfunction "SPEEED")
			(pintype "input")
		)
		(pad "9" smd roundrect
			(at 0.8 0.598)
			(size 0.6 0.2)
			(layers "F.Cu" "F.Mask" "F.Paste")
			(roundrect_rratio 0.2272727273)
			(net 927 "/USB PHY/USB_USR_D-")
			(pinfunction "D-")
			(pintype "bidirectional")
		)
		(pad "10" smd roundrect
			(at 0.8 0.2)
			(size 0.6 0.2)
			(layers "F.Cu" "F.Mask" "F.Paste")
			(roundrect_rratio 0.2272727273)
			(net 928 "/USB PHY/USB_USR_D+")
			(pinfunction "D+")
			(pintype "bidirectional")
		)
		(pad "11" smd roundrect
			(at 0.8 -0.202)
			(size 0.6 0.2)
			(layers "F.Cu" "F.Mask" "F.Paste")
			(roundrect_rratio 0.2272727273)
			(net 639 "/FPGA Bank 12 & 13/USB_USER.VPO")
			(pinfunction "VPO")
			(pintype "input")
		)
		(pad "12" smd roundrect
			(at 0.8 -0.6)
			(size 0.6 0.2)
			(layers "F.Cu" "F.Mask" "F.Paste")
			(roundrect_rratio 0.2272727273)
			(net 693 "/FPGA Bank 12 & 13/USB_USER.VMO")
			(pinfunction "VMO")
			(pintype "input")
		)
		(pad "13" smd roundrect
			(at 0.598 -1.2 90)
			(size 0.6 0.2)
			(layers "F.Cu" "F.Mask" "F.Paste")
			(roundrect_rratio 0.2272727273)
			(net 24 "+3V3")
			(pinfunction "VREG")
			(pintype "power_out")
		)
		(pad "14" smd roundrect
			(at 0.2 -1.2 90)
			(size 0.6 0.2)
			(layers "F.Cu" "F.Mask" "F.Paste")
			(roundrect_rratio 0.2272727273)
			(net 24 "+3V3")
			(pinfunction "VCC")
			(pintype "power_in")
		)
		(pad "15" smd roundrect
			(at -0.202 -1.2 90)
			(size 0.6 0.2)
			(layers "F.Cu" "F.Mask" "F.Paste")
			(roundrect_rratio 0.2272727273)
			(net 926 "/USB PHY/USB_USR_VPU")
			(pinfunction "VPU")
			(pintype "input")
		)
		(pad "16" smd roundrect
			(at -0.6 -1.2 90)
			(size 0.6 0.2)
			(layers "F.Cu" "F.Mask" "F.Paste")
			(roundrect_rratio 0.2272727273)
			(net 619 "/FPGA Bank 12 & 13/USB_USER.SCON")
			(pinfunction "SOFTCON")
			(pintype "input")
		)
	)
)
